# BASEBOARD_FAB2 (Tioga Pass) — schematic netlist excerpt (pin names and nets, part order shuffled) for the footprints in the layout excerpt that follows; sources: Cadence DE-HDL packaged netlist, KiCad conversion of Wiwynn_Tioga_Pass_MB.brd

R12W6  665KR5B-1-GP  0.1%  pkg SMD-RG3  page 197 : \1\ = P12V_STBY ; \2\ = VR_PVDDQ_DEF_AIINSEN
R3P11  RES  0.0 5% CHIP  pkg 0402  page 211 : A = SVID_DIO0_CPU0_R ; B = SVID_VDIO_PVCCIO_CPU0
R9W34  RES  4.75K 1% CHIP  pkg 0402  page 158 : A = P3V3_STBY ; B = UART_BMC_RXD5

(kicad_pcb
	(version 20260206)
	(generator "pcbnew")
	(generator_version "10.0")
	(general
		(thickness 1.6)
		(legacy_teardrops no)
	)
	(paper "A4")
	(title_block
		(title "Wiwynn_Tioga_Pass_MB.brd")
		(comment 1 "Tioga Pass / footprints 3531-3533 of 4770")
	)
	(layers
		(0 "F.Cu" signal "TOP")
		(4 "In1.Cu" signal "L2GND")
		(6 "In2.Cu" signal "L3")
		(8 "In3.Cu" signal "L4GND")
		(10 "In4.Cu" signal "L5")
		(12 "In5.Cu" signal "L6GND")
		(14 "In6.Cu" signal "L7VCC")
		(16 "In7.Cu" signal "L8VCC")
		(18 "In8.Cu" signal "L9GND")
		(20 "In9.Cu" signal "L10")
		(22 "In10.Cu" signal "L11GND")
		(24 "In11.Cu" signal "L12")
		(26 "In12.Cu" signal "L13GND")
		(2 "B.Cu" signal "BOTTOM")
		(9 "F.Adhes" user "F.Adhesive")
		(11 "B.Adhes" user "B.Adhesive")
		(13 "F.Paste" user "Package Geometry/Pastemask Top")
		(15 "B.Paste" user "Package Geometry/Pastemask Bottom")
		(5 "F.SilkS" user "Ref Des/Silkscreen Top")
		(7 "B.SilkS" user "Ref Des/Silkscreen Bottom")
		(1 "F.Mask" user "Board Geometry/Soldermask Top")
		(3 "B.Mask" user "Board Geometry/Soldermask Bottom")
		(17 "Dwgs.User" user "User.Drawings")
		(19 "Cmts.User" user "User.Comments")
		(21 "Eco1.User" user "User.Eco1")
		(23 "Eco2.User" user "User.Eco2")
		(25 "Edge.Cuts" user "Board Geometry/Outline")
		(27 "Margin" user)
		(31 "F.CrtYd" user "Package Geometry/Place Bound Top")
		(29 "B.CrtYd" user "Package Geometry/Place Bound Bottom")
		(35 "F.Fab" user "Ref Des/Assembly Top")
		(33 "B.Fab" user "Ref Des/Assembly Bottom")
	)
	(footprint ""
		(layer "B.Cu")
		(at 487.7054 -36.3474 90)
		(property "Reference" "R9W34"
			(at 0.8382 -0.67818 90)
			(unlocked yes)
			(layer "B.SilkS")
			(effects
				(font
					(size 0.4064 0.254)
					(thickness 0.1524)
				)
				(justify left mirror)
			)
		)
		(property "Value" ""
			(at 0 0 90)
			(layer "B.Fab")
			(effects
				(font
					(size 1.27 1.27)
				)
				(justify mirror)
			)
		)
		(duplicate_pad_numbers_are_jumpers no)
		(fp_poly
			(pts
				(xy 0.2794 -0.1016) (xy -0.2794 -0.1016) (xy -0.2794 0.9906) (xy 0.2794 0.9906)
			)
			(stroke
				(width 0)
				(type default)
			)
			(fill no)
			(layer "B.CrtYd")
		)
		(fp_line
			(start 0.2794 -0.1016)
			(end 0.2794 0.9906)
			(stroke
				(width 0.1)
				(type default)
			)
			(layer "B.Fab")
		)
		(fp_line
			(start -0.2794 -0.1016)
			(end 0.2794 -0.1016)
			(stroke
				(width 0.1)
				(type default)
			)
			(layer "B.Fab")
		)
		(fp_line
			(start 0.2794 0.9906)
			(end -0.2794 0.9906)
			(stroke
				(width 0.1)
				(type default)
			)
			(layer "B.Fab")
		)
		(fp_line
			(start -0.2794 0.9906)
			(end -0.2794 -0.1016)
			(stroke
				(width 0.1)
				(type default)
			)
			(layer "B.Fab")
		)
		(pad "1" smd rect
			(at 0 0 270)
			(size 0.508 0.508)
			(layers "B.Cu" "B.Mask" "B.Paste")
			(net "P3V3_STBY")
		)
		(pad "2" smd rect
			(at 0 0.889 270)
			(size 0.508 0.508)
			(layers "B.Cu" "B.Mask" "B.Paste")
			(net "UART_BMC_RXD5")
		)
		(zone
			(layer "B.Cu")
			(hatch none 0.5)
			(connect_pads
				(clearance 0)
			)
			(min_thickness 0.25)
			(keepout
				(tracks allowed)
				(vias not_allowed)
				(pads allowed)
				(copperpour not_allowed)
				(footprints allowed)
			)
			(placement
				(enabled no)
				(sheetname "")
			)
			(fill
				(thermal_gap 0.5)
				(thermal_bridge_width 0.5)
				(island_removal_mode 0)
			)
			(polygon
				(pts
					(xy 487.9594 -36.6014) (xy 487.9594 -36.0934) (xy 488.3404 -36.0934) (xy 488.3404 -36.6014)
				)
			)
		)
		(zone
			(layer "B.Cu")
			(hatch none 0.5)
			(connect_pads
				(clearance 0)
			)
			(min_thickness 0.25)
			(keepout
				(tracks not_allowed)
				(vias allowed)
				(pads allowed)
				(copperpour not_allowed)
				(footprints allowed)
			)
			(placement
				(enabled no)
				(sheetname "")
			)
			(fill
				(thermal_gap 0.5)
				(thermal_bridge_width 0.5)
				(island_removal_mode 0)
			)
			(polygon
				(pts
					(xy 488.3404 -36.6014) (xy 488.3404 -36.0934) (xy 487.9594 -36.0934) (xy 487.9594 -36.6014)
				)
			)
		)
	)
	(footprint ""
		(layer "B.Cu")
		(at 355.41966 -135.1915 -90)
		(property "Reference" "R12W6"
			(at 0 0 90)
			(layer "B.SilkS")
			(hide yes)
			(effects
				(font
					(size 1.27 1.27)
				)
				(justify mirror)
			)
		)
		(property "Value" "*"
			(at 0 -8.9535 270)
			(unlocked yes)
			(layer "B.Fab")
			(hide yes)
			(effects
				(font
					(size 1.27 1.016)
					(thickness 0.1524)
				)
				(justify mirror)
			)
		)
		(property "Device Type" "665KR5B-1-GP_SMD-RG3-665KR5B-1A"
			(at 0 -10.6299 270)
			(unlocked yes)
			(layer "B.Fab")
			(hide yes)
			(effects
				(font
					(size 1.27 1.016)
					(thickness 0.1524)
				)
				(justify mirror)
			)
		)
		(duplicate_pad_numbers_are_jumpers no)
		(fp_line
			(start -0.889 1.7018)
			(end -0.889 -0.508)
			(stroke
				(width 0.1524)
				(type default)
			)
			(layer "B.SilkS")
		)
		(fp_line
			(start 0.889 1.7018)
			(end -0.889 1.7018)
			(stroke
				(width 0.1524)
				(type default)
			)
			(layer "B.SilkS")
		)
		(fp_line
			(start 0.889 0.0762)
			(end 0.889 1.7018)
			(stroke
				(width 0.1524)
				(type default)
			)
			(layer "B.SilkS")
		)
		(fp_line
			(start -0.889 -1.7018)
			(end -0.889 -0.381)
			(stroke
				(width 0.1524)
				(type default)
			)
			(layer "B.SilkS")
		)
		(fp_line
			(start -0.889 -1.7018)
			(end 0.889 -1.7018)
			(stroke
				(width 0.1524)
				(type default)
			)
			(layer "B.SilkS")
		)
		(fp_line
			(start 0.889 -1.7018)
			(end 0.889 0.2794)
			(stroke
				(width 0.1524)
				(type default)
			)
			(layer "B.SilkS")
		)
		(fp_poly
			(pts
				(xy -0.9652 -1.778) (xy -0.9652 1.778) (xy 0.9652 1.778) (xy 0.9652 -1.778)
			)
			(stroke
				(width 0)
				(type default)
			)
			(fill no)
			(layer "B.CrtYd")
		)
		(fp_rect
			(start 0.9652 1.778)
			(end -0.9652 -1.778)
			(stroke
				(width 0)
				(type default)
			)
			(fill no)
			(layer "B.Fab")
		)
		(pad "1" smd rect
			(at 0 -0.9652 90)
			(size 1.397 1.143)
			(layers "B.Cu" "B.Mask" "B.Paste")
			(net "P12V_STBY")
		)
		(pad "2" smd rect
			(at 0 0.9652 90)
			(size 1.397 1.143)
			(layers "B.Cu" "B.Mask" "B.Paste")
			(net "VR_PVDDQ_DEF_AIINSEN")
		)
	)
	(footprint ""
		(layer "B.Cu")
		(at 341.1982 -87.4522 90)
		(property "Reference" "R3P11"
			(at 0 0 90)
			(layer "B.SilkS")
			(hide yes)
			(effects
				(font
					(size 1.27 1.27)
				)
				(justify mirror)
			)
		)
		(property "Value" ""
			(at 0 0 90)
			(layer "B.Fab")
			(effects
				(font
					(size 1.27 1.27)
				)
				(justify mirror)
			)
		)
		(duplicate_pad_numbers_are_jumpers no)
		(fp_poly
			(pts
				(xy 0.2794 -0.1016) (xy -0.2794 -0.1016) (xy -0.2794 0.9906) (xy 0.2794 0.9906)
			)
			(stroke
				(width 0)
				(type default)
			)
			(fill no)
			(layer "B.CrtYd")
		)
		(fp_line
			(start 0.2794 -0.1016)
			(end 0.2794 0.9906)
			(stroke
				(width 0.1)
				(type default)
			)
			(layer "B.Fab")
		)
		(fp_line
			(start -0.2794 -0.1016)
			(end 0.2794 -0.1016)
			(stroke
				(width 0.1)
				(type default)
			)
			(layer "B.Fab")
		)
		(fp_line
			(start 0.2794 0.9906)
			(end -0.2794 0.9906)
			(stroke
				(width 0.1)
				(type default)
			)
			(layer "B.Fab")
		)
		(fp_line
			(start -0.2794 0.9906)
			(end -0.2794 -0.1016)
			(stroke
				(width 0.1)
				(type default)
			)
			(layer "B.Fab")
		)
		(pad "1" smd rect
			(at 0 0 270)
			(size 0.508 0.508)
			(layers "B.Cu" "B.Mask" "B.Paste")
			(net "SVID_DIO0_CPU0_R")
		)
		(pad "2" smd rect
			(at 0 0.889 270)
			(size 0.508 0.508)
			(layers "B.Cu" "B.Mask" "B.Paste")
			(net "SVID_VDIO_PVCCIO_CPU0")
		)
		(zone
			(layer "B.Cu")
			(hatch none 0.5)
			(connect_pads
				(clearance 0)
			)
			(min_thickness 0.25)
			(keepout
				(tracks allowed)
				(vias not_allowed)
				(pads allowed)
				(copperpour not_allowed)
				(footprints allowed)
			)
			(placement
				(enabled no)
				(sheetname "")
			)
			(fill
				(thermal_gap 0.5)
				(thermal_bridge_width 0.5)
				(island_removal_mode 0)
			)
			(polygon
				(pts
					(xy 341.4522 -87.7062) (xy 341.4522 -87.1982) (xy 341.8332 -87.1982) (xy 341.8332 -87.7062)
				)
			)
		)
		(zone
			(layer "B.Cu")
			(hatch none 0.5)
			(connect_pads
				(clearance 0)
			)
			(min_thickness 0.25)
			(keepout
				(tracks not_allowed)
				(vias allowed)
				(pads allowed)
				(copperpour not_allowed)
				(footprints allowed)
			)
			(placement
				(enabled no)
				(sheetname "")
			)
			(fill
				(thermal_gap 0.5)
				(thermal_bridge_width 0.5)
				(island_removal_mode 0)
			)
			(polygon
				(pts
					(xy 341.8332 -87.7062) (xy 341.8332 -87.1982) (xy 341.4522 -87.1982) (xy 341.4522 -87.7062)
				)
			)
		)
	)
)
